(kicad_pcb
	(version 20241229)
	(generator "pcbnew")
	(generator_version "9.0")
	(general
		(thickness 1.6642)
		(legacy_teardrops no)
	)
	(paper "A3")
	(title_block
		(title "PolarFire SoM")
		(date "2025-07-22")
		(rev "1.1.4")
		(company "Antmicro Ltd")
		(comment 1 "www.antmicro.com")
		(comment 9 "footprints 351-354 of 470")
	)
	(layers
		(0 "F.Cu" mixed)
		(4 "In1.Cu" power)
		(6 "In2.Cu" signal)
		(8 "In3.Cu" power)
		(10 "In4.Cu" signal)
		(12 "In5.Cu" power)
		(14 "In6.Cu" power)
		(16 "In7.Cu" signal)
		(18 "In8.Cu" power)
		(20 "In9.Cu" signal)
		(22 "In10.Cu" power)
		(24 "In11.Cu" signal)
		(26 "In12.Cu" signal)
		(2 "B.Cu" mixed)
		(9 "F.Adhes" user "F.Adhesive")
		(11 "B.Adhes" user "B.Adhesive")
		(13 "F.Paste" user)
		(15 "B.Paste" user)
		(5 "F.SilkS" user "F.Silkscreen")
		(7 "B.SilkS" user "B.Silkscreen")
		(1 "F.Mask" user)
		(3 "B.Mask" user)
		(17 "Dwgs.User" user "User.Drawings")
		(19 "Cmts.User" user "User.Comments")
		(21 "Eco1.User" user "User.Eco1")
		(23 "Eco2.User" user "User.Eco2")
		(25 "Edge.Cuts" user)
		(27 "Margin" user)
		(31 "F.CrtYd" user "F.Courtyard")
		(29 "B.CrtYd" user "B.Courtyard")
		(35 "F.Fab" user)
		(33 "B.Fab" user)
	)
	(footprint "antmicro-footprints:XSON-8_1x1.95mm_P0.5mm"
		(layer "B.Cu")
		(at 208.45 137.75 90)
		(property "Reference" "U21"
			(at -1.9 0.55 180)
			(layer "B.SilkS")
			(effects
				(font
					(size 0.7 0.7)
					(thickness 0.15)
				)
				(justify right bottom mirror)
			)
		)
		(property "Value" "NTS0102_XSON"
			(at 0 -2.2 90)
			(layer "B.Fab")
			(hide yes)
			(effects
				(font
					(size 0.7 0.7)
					(thickness 0.15)
				)
				(justify right bottom mirror)
			)
		)
		(property "Datasheet" "http://www.farnell.com/datasheets/1760723.pdf"
			(at 0 0 90)
			(layer "F.Fab")
			(hide yes)
			(effects
				(font
					(size 1.27 1.27)
					(thickness 0.15)
				)
			)
		)
		(property "Description" "Transceiver, 1.65 V to 3.6 V, XSON-8"
			(at 0 0 90)
			(layer "F.Fab")
			(hide yes)
			(effects
				(font
					(size 1.27 1.27)
					(thickness 0.15)
				)
			)
		)
		(property "Author" "Antmicro"
			(at 346.2 -70.7 0)
			(layer "B.Fab")
			(hide yes)
			(effects
				(font
					(size 1 1)
					(thickness 0.15)
				)
				(justify mirror)
			)
		)
		(property "License" "Apache-2.0"
			(at 346.2 -70.7 0)
			(layer "B.Fab")
			(hide yes)
			(effects
				(font
					(size 1 1)
					(thickness 0.15)
				)
				(justify mirror)
			)
		)
		(property "MPN" "NTS0102GT"
			(at 346.2 -70.7 0)
			(layer "B.Fab")
			(hide yes)
			(effects
				(font
					(size 1 1)
					(thickness 0.15)
				)
				(justify mirror)
			)
		)
		(property "Manufacturer" "NXP"
			(at 346.2 -70.7 0)
			(layer "B.Fab")
			(hide yes)
			(effects
				(font
					(size 1 1)
					(thickness 0.15)
				)
				(justify mirror)
			)
		)
		(sheetname "/FPGA GPIO/")
		(sheetfile "fpga-gpio.kicad_sch")
		(attr smd)
		(fp_line
			(start 0.5 -1.1)
			(end -0.5 -1.1)
			(stroke
				(width 0.15)
				(type solid)
			)
			(layer "B.SilkS")
		)
		(fp_line
			(start -0.5 1.1)
			(end 0.5 1.1)
			(stroke
				(width 0.15)
				(type solid)
			)
			(layer "B.SilkS")
		)
		(fp_circle
			(center -0.75 1.1)
			(end -0.701 1.1)
			(stroke
				(width 0.15)
				(type solid)
			)
			(fill no)
			(layer "B.SilkS")
		)
		(fp_rect
			(start -0.8 1.2)
			(end 0.8 -1.2)
			(stroke
				(width 0.05)
				(type solid)
			)
			(fill no)
			(layer "B.CrtYd")
		)
		(fp_line
			(start 0.5305 -1)
			(end -0.5305 -1)
			(stroke
				(width 0.15)
				(type solid)
			)
			(layer "B.Fab")
		)
		(fp_line
			(start -0.5305 -1)
			(end -0.5305 1.001)
			(stroke
				(width 0.15)
				(type solid)
			)
			(layer "B.Fab")
		)
		(fp_line
			(start 0.5305 1.001)
			(end 0.5305 -1)
			(stroke
				(width 0.15)
				(type solid)
			)
			(layer "B.Fab")
		)
		(fp_line
			(start -0.5305 1.001)
			(end 0.5305 1.001)
			(stroke
				(width 0.15)
				(type solid)
			)
			(layer "B.Fab")
		)
		(fp_text user "Author: Antmicro"
			(at -0.527 -7.105 270)
			(layer "B.Fab")
			(effects
				(font
					(size 0.7 0.7)
					(thickness 0.15)
				)
				(justify left bottom mirror)
			)
		)
		(fp_text user "License: Apache-2.0"
			(at -0.527 -8.306 270)
			(layer "B.Fab")
			(effects
				(font
					(size 0.7 0.7)
					(thickness 0.15)
				)
				(justify left bottom mirror)
			)
		)
		(fp_text user "${REFERENCE}"
			(at -0.527 -5.905 270)
			(layer "B.Fab")
			(effects
				(font
					(size 0.7 0.7)
					(thickness 0.15)
				)
				(justify left bottom mirror)
			)
		)
		(pad "1" smd roundrect
			(at -0.45 0.75 270)
			(size 0.6 0.3)
			(layers "B.Cu" "B.Mask" "B.Paste")
			(roundrect_rratio 0.25)
			(net 202 "PCIe_nRST")
			(pinfunction "B_{2}")
			(pintype "bidirectional")
		)
		(pad "2" smd roundrect
			(at -0.45 0.25 270)
			(size 0.6 0.25)
			(layers "B.Cu" "B.Mask" "B.Paste")
			(roundrect_rratio 0.25)
			(net 417 "GND")
			(pinfunction "GND")
			(pintype "power_in")
		)
		(pad "3" smd roundrect
			(at -0.45 -0.25 270)
			(size 0.6 0.25)
			(layers "B.Cu" "B.Mask" "B.Paste")
			(roundrect_rratio 0.25)
			(net 649 "VDD")
			(pinfunction "VCC_{A}")
			(pintype "power_in")
		)
		(pad "4" smd roundrect
			(at -0.45 -0.75 270)
			(size 0.6 0.3)
			(layers "B.Cu" "B.Mask" "B.Paste")
			(roundrect_rratio 0.25)
			(net 543 "/FPGA GPIO/PCIe_nRST_PF")
			(pinfunction "A_{2}")
			(pintype "bidirectional")
		)
		(pad "5" smd roundrect
			(at 0.45 -0.75 270)
			(size 0.6 0.3)
			(layers "B.Cu" "B.Mask" "B.Paste")
			(roundrect_rratio 0.25)
			(net 544 "/FPGA GPIO/PCIe_CLK_nREQ_PF")
			(pinfunction "A_{1}")
			(pintype "bidirectional")
		)
		(pad "6" smd roundrect
			(at 0.45 -0.25 270)
			(size 0.6 0.25)
			(layers "B.Cu" "B.Mask" "B.Paste")
			(roundrect_rratio 0.25)
			(net 649 "VDD")
			(pinfunction "OE")
			(pintype "input")
		)
		(pad "7" smd roundrect
			(at 0.45 0.25 270)
			(size 0.6 0.25)
			(layers "B.Cu" "B.Mask" "B.Paste")
			(roundrect_rratio 0.25)
			(net 50 "+3V3")
			(pinfunction "VCC_{B}")
			(pintype "power_in")
		)
		(pad "8" smd roundrect
			(at 0.45 0.75 270)
			(size 0.6 0.3)
			(layers "B.Cu" "B.Mask" "B.Paste")
			(roundrect_rratio 0.25)
			(net 200 "PCIe_CLK_nREQ")
			(pinfunction "B_{1}")
			(pintype "bidirectional")
		)
	)
	(footprint "antmicro-footprints:TP_SMD_0.75mm"
		(layer "B.Cu")
		(at 184 140.4 180)
		(property "Reference" "TP5"
			(at -0.01 -0.85 0)
			(layer "B.SilkS")
			(hide yes)
			(effects
				(font
					(size 0.7 0.7)
					(thickness 0.15)
				)
				(justify left bottom mirror)
			)
		)
		(property "Value" "TP_0.75mm_SMD"
			(at 0 -1.2 0)
			(layer "B.Fab")
			(hide yes)
			(effects
				(font
					(size 0.7 0.7)
					(thickness 0.15)
				)
				(justify left bottom mirror)
			)
		)
		(property "Description" "SMT test point"
			(at 0 0 0)
			(layer "B.Fab")
			(hide yes)
			(effects
				(font
					(size 1.27 1.27)
					(thickness 0.15)
				)
				(justify mirror)
			)
		)
		(property "MPN" ""
			(at 0 0 0)
			(unlocked yes)
			(layer "B.Fab")
			(hide yes)
			(effects
				(font
					(size 1 1)
					(thickness 0.15)
				)
				(justify mirror)
			)
		)
		(property "Manufacturer" ""
			(at 0 0 0)
			(unlocked yes)
			(layer "B.Fab")
			(hide yes)
			(effects
				(font
					(size 1 1)
					(thickness 0.15)
				)
				(justify mirror)
			)
		)
		(property "Author" "Antmicro"
			(at 0 0 0)
			(unlocked yes)
			(layer "B.Fab")
			(hide yes)
			(effects
				(font
					(size 1 1)
					(thickness 0.15)
				)
				(justify mirror)
			)
		)
		(property "License" "Apache-2.0"
			(at 0 0 0)
			(unlocked yes)
			(layer "B.Fab")
			(hide yes)
			(effects
				(font
					(size 1 1)
					(thickness 0.15)
				)
				(justify mirror)
			)
		)
		(property "Public" "False"
			(at 0 0 0)
			(unlocked yes)
			(layer "B.Fab")
			(hide yes)
			(effects
				(font
					(size 1 1)
					(thickness 0.15)
				)
				(justify mirror)
			)
		)
		(sheetname "/Supply/")
		(sheetfile "supply.kicad_sch")
		(attr exclude_from_pos_files exclude_from_bom)
		(fp_circle
			(center 0 0)
			(end 0.475 0)
			(stroke
				(width 0.05)
				(type default)
			)
			(fill no)
			(layer "B.CrtYd")
		)
		(fp_text user "${REFERENCE}"
			(at -0.4 -2.7 0)
			(layer "B.Fab")
			(effects
				(font
					(size 0.7 0.7)
					(thickness 0.15)
				)
				(justify left bottom mirror)
			)
		)
		(fp_text user "License: Apache-2.0"
			(at -0.4 -5.101 0)
			(layer "B.Fab")
			(effects
				(font
					(size 0.7 0.7)
					(thickness 0.15)
				)
				(justify left bottom mirror)
			)
		)
		(fp_text user "Author: Antmicro"
			(at -0.4 -3.901 0)
			(layer "B.Fab")
			(effects
				(font
					(size 0.7 0.7)
					(thickness 0.15)
				)
				(justify left bottom mirror)
			)
		)
		(pad "1" smd circle
			(at 0 0 180)
			(size 0.75 0.75)
			(layers "B.Cu" "B.Mask")
			(net 272 "/Supply/SENSE3_P")
			(pinfunction "1")
			(pintype "passive")
		)
	)
	(footprint "antmicro-footprints:R_0402_1005Metric"
		(layer "B.Cu")
		(at 222.08 131.6)
		(descr "Resistor SMD 0402")
		(tags "resistor SMD 0402")
		(property "Reference" "R80"
			(at 1.07 1.3 180)
			(layer "B.SilkS")
			(effects
				(font
					(size 0.7 0.7)
					(thickness 0.15)
				)
				(justify left bottom mirror)
			)
		)
		(property "Value" "R_100k_0402"
			(at -1.011843 -1.772047 180)
			(layer "B.Fab")
			(hide yes)
			(effects
				(font
					(size 0.7 0.7)
					(thickness 0.15)
				)
				(justify left bottom mirror)
			)
		)
		(property "Datasheet" "https://www.bourns.com/docs/product-datasheets/cr.pdf"
			(at 0 0 0)
			(layer "F.Fab")
			(hide yes)
			(effects
				(font
					(size 1.27 1.27)
					(thickness 0.15)
				)
			)
		)
		(property "Description" "SMD Chip Resistor, 100 kohm, ± 1%, 62.5 mW, 0402 [1005 Metric], Thick Film, General Purpose"
			(at 0 0 0)
			(layer "F.Fab")
			(hide yes)
			(effects
				(font
					(size 1.27 1.27)
					(thickness 0.15)
				)
			)
		)
		(property "Author" "Antmicro"
			(at 0 0 0)
			(layer "B.Fab")
			(hide yes)
			(effects
				(font
					(size 1 1)
					(thickness 0.15)
				)
				(justify mirror)
			)
		)
		(property "License" "Apache-2.0"
			(at 0 0 0)
			(layer "B.Fab")
			(hide yes)
			(effects
				(font
					(size 1 1)
					(thickness 0.15)
				)
				(justify mirror)
			)
		)
		(property "MPN" "CR0402-FX-1003GLF"
			(at 0 0 0)
			(layer "B.Fab")
			(hide yes)
			(effects
				(font
					(size 1 1)
					(thickness 0.15)
				)
				(justify mirror)
			)
		)
		(property "Manufacturer" "Bourns"
			(at 0 0 0)
			(layer "B.Fab")
			(hide yes)
			(effects
				(font
					(size 1 1)
					(thickness 0.15)
				)
				(justify mirror)
			)
		)
		(property "Public" ""
			(at 0 0 0)
			(layer "B.Fab")
			(hide yes)
			(effects
				(font
					(size 1 1)
					(thickness 0.15)
				)
				(justify mirror)
			)
		)
		(property "Tolerance" "1%"
			(at 0 0 0)
			(layer "B.Fab")
			(hide yes)
			(effects
				(font
					(size 1 1)
					(thickness 0.15)
				)
				(justify mirror)
			)
		)
		(property "Val" "100k"
			(at 0 0 0)
			(layer "B.Fab")
			(hide yes)
			(effects
				(font
					(size 1 1)
					(thickness 0.15)
				)
				(justify mirror)
			)
		)
		(sheetname "/FPGA GPIO/")
		(sheetfile "fpga-gpio.kicad_sch")
		(attr smd)
		(fp_rect
			(start -0.925 0.47)
			(end 0.925 -0.47)
			(stroke
				(width 0.05)
				(type default)
			)
			(fill no)
			(layer "B.CrtYd")
		)
		(fp_rect
			(start -0.5 0.25)
			(end 0.5 -0.25)
			(stroke
				(width 0.15)
				(type solid)
			)
			(fill no)
			(layer "B.Fab")
		)
		(fp_text user "License: Apache-2.0"
			(at -0.95 -5.169 180)
			(layer "B.Fab")
			(effects
				(font
					(size 0.7 0.7)
					(thickness 0.15)
				)
				(justify left bottom mirror)
			)
		)
		(fp_text user "${REFERENCE}"
			(at -0.95 -3.168 180)
			(layer "B.Fab")
			(effects
				(font
					(size 0.7 0.7)
					(thickness 0.15)
				)
				(justify left bottom mirror)
			)
		)
		(fp_text user "Author: Antmicro"
			(at -0.95 -4.169 180)
			(layer "B.Fab")
			(effects
				(font
					(size 0.7 0.7)
					(thickness 0.15)
				)
				(justify left bottom mirror)
			)
		)
		(pad "1" smd roundrect
			(at -0.48 0)
			(size 0.59 0.64)
			(layers "B.Cu" "B.Mask" "B.Paste")
			(roundrect_rratio 0.25)
			(net 417 "GND")
			(pintype "passive")
		)
		(pad "2" smd roundrect
			(at 0.48 0)
			(size 0.59 0.64)
			(layers "B.Cu" "B.Mask" "B.Paste")
			(roundrect_rratio 0.25)
			(net 224 "/FPGA GPIO/USER_LED_B")
			(pintype "passive")
		)
	)
	(footprint "antmicro-footprints:C_0402_1005Metric"
		(layer "B.Cu")
		(at 175.475 142.9675 -90)
		(descr "Capacitor SMD 0402")
		(tags "capacitor SMD 0402")
		(property "Reference" "C108"
			(at 3.6525 0.435 90)
			(layer "B.SilkS")
			(effects
				(font
					(size 0.7 0.7)
					(thickness 0.15)
				)
				(justify right top mirror)
			)
		)
		(property "Value" "C_22u_0402"
			(at -1.022927 -2.155213 90)
			(layer "B.Fab")
			(hide yes)
			(effects
				(font
					(size 0.7 0.7)
					(thickness 0.15)
				)
				(justify left bottom mirror)
			)
		)
		(property "Datasheet" "https://www.murata.com/products/productdetail?partno=GRM158R60J226ME01%23"
			(at 0 0 90)
			(layer "F.Fab")
			(hide yes)
			(effects
				(font
					(size 1.27 1.27)
					(thickness 0.15)
				)
			)
		)
		(property "Description" "SMD Multilayer Ceramic Capacitor, 22 uF, 4 V, 0402 [1005 Metric], X6S"
			(at 0 0 90)
			(layer "F.Fab")
			(hide yes)
			(effects
				(font
					(size 1.27 1.27)
					(thickness 0.15)
				)
			)
		)
		(property "Author" "Antmicro"
			(at 32.5075 318.4425 0)
			(layer "B.Fab")
			(hide yes)
			(effects
				(font
					(size 1 1)
					(thickness 0.15)
				)
				(justify mirror)
			)
		)
		(property "Dielectric" ""
			(at 32.5075 318.4425 0)
			(layer "B.Fab")
			(hide yes)
			(effects
				(font
					(size 1 1)
					(thickness 0.15)
				)
				(justify mirror)
			)
		)
		(property "License" "Apache-2.0"
			(at 32.5075 318.4425 0)
			(layer "B.Fab")
			(hide yes)
			(effects
				(font
					(size 1 1)
					(thickness 0.15)
				)
				(justify mirror)
			)
		)
		(property "MPN" "GRM158R60J226ME01D"
			(at 32.5075 318.4425 0)
			(layer "B.Fab")
			(hide yes)
			(effects
				(font
					(size 1 1)
					(thickness 0.15)
				)
				(justify mirror)
			)
		)
		(property "Manufacturer" "Murata"
			(at 32.5075 318.4425 0)
			(layer "B.Fab")
			(hide yes)
			(effects
				(font
					(size 1 1)
					(thickness 0.15)
				)
				(justify mirror)
			)
		)
		(property "Public" ""
			(at 32.5075 318.4425 0)
			(layer "B.Fab")
			(hide yes)
			(effects
				(font
					(size 1 1)
					(thickness 0.15)
				)
				(justify mirror)
			)
		)
		(property "Val" "22u"
			(at 32.5075 318.4425 0)
			(layer "B.Fab")
			(hide yes)
			(effects
				(font
					(size 1 1)
					(thickness 0.15)
				)
				(justify mirror)
			)
		)
		(property "Voltage" ""
			(at 32.5075 318.4425 0)
			(layer "B.Fab")
			(hide yes)
			(effects
				(font
					(size 1 1)
					(thickness 0.15)
				)
				(justify mirror)
			)
		)
		(sheetname "/Supply/")
		(sheetfile "supply.kicad_sch")
		(attr smd)
		(fp_rect
			(start -0.925 0.47)
			(end 0.925 -0.47)
			(stroke
				(width 0.05)
				(type default)
			)
			(fill no)
			(layer "B.CrtYd")
		)
		(fp_line
			(start -0.494 0.25)
			(end 0.504 0.25)
			(stroke
				(width 0.15)
				(type solid)
			)
			(layer "B.Fab")
		)
		(fp_line
			(start 0.504 0.25)
			(end 0.504 -0.248)
			(stroke
				(width 0.15)
				(type solid)
			)
			(layer "B.Fab")
		)
		(fp_line
			(start -0.494 -0.248)
			(end -0.494 0.25)
			(stroke
				(width 0.15)
				(type solid)
			)
			(layer "B.Fab")
		)
		(fp_line
			(start 0.504 -0.248)
			(end -0.494 -0.248)
			(stroke
				(width 0.15)
				(type solid)
			)
			(layer "B.Fab")
		)
		(fp_text user "Author: Antmicro"
			(at -0.939 -3.399 90)
			(layer "B.Fab")
			(effects
				(font
					(size 0.7 0.7)
					(thickness 0.15)
				)
				(justify left bottom mirror)
			)
		)
		(fp_text user "${REFERENCE}"
			(at -0.939 -4.599 90)
			(layer "B.Fab")
			(effects
				(font
					(size 0.7 0.7)
					(thickness 0.15)
				)
				(justify left bottom mirror)
			)
		)
		(fp_text user "License: Apache-2.0"
			(at -0.939 -5.799 90)
			(layer "B.Fab")
			(effects
				(font
					(size 0.7 0.7)
					(thickness 0.15)
				)
				(justify left bottom mirror)
			)
		)
		(pad "1" smd roundrect
			(at -0.48 0 270)
			(size 0.59 0.64)
			(layers "B.Cu" "B.Mask" "B.Paste")
			(roundrect_rratio 0.25)
			(net 417 "GND")
			(pintype "passive")
		)
		(pad "2" smd roundrect
			(at 0.48 0 270)
			(size 0.59 0.64)
			(layers "B.Cu" "B.Mask" "B.Paste")
			(roundrect_rratio 0.25)
			(net 406 "/Supply/SENSE2_P")
			(pintype "passive")
		)
	)
)
